(kicad_pcb
	(version 20241229)
	(generator "pcbnew")
	(generator_version "9.0")
	(general
		(thickness 1.6642)
		(legacy_teardrops no)
	)
	(paper "A3")
	(title_block
		(title "PolarFire SoM")
		(date "2025-07-22")
		(rev "1.1.4")
		(company "Antmicro Ltd")
		(comment 1 "www.antmicro.com")
		(comment 9 "footprints 225-228 of 470")
	)
	(layers
		(0 "F.Cu" mixed)
		(4 "In1.Cu" power)
		(6 "In2.Cu" signal)
		(8 "In3.Cu" power)
		(10 "In4.Cu" signal)
		(12 "In5.Cu" power)
		(14 "In6.Cu" power)
		(16 "In7.Cu" signal)
		(18 "In8.Cu" power)
		(20 "In9.Cu" signal)
		(22 "In10.Cu" power)
		(24 "In11.Cu" signal)
		(26 "In12.Cu" signal)
		(2 "B.Cu" mixed)
		(9 "F.Adhes" user "F.Adhesive")
		(11 "B.Adhes" user "B.Adhesive")
		(13 "F.Paste" user)
		(15 "B.Paste" user)
		(5 "F.SilkS" user "F.Silkscreen")
		(7 "B.SilkS" user "B.Silkscreen")
		(1 "F.Mask" user)
		(3 "B.Mask" user)
		(17 "Dwgs.User" user "User.Drawings")
		(19 "Cmts.User" user "User.Comments")
		(21 "Eco1.User" user "User.Eco1")
		(23 "Eco2.User" user "User.Eco2")
		(25 "Edge.Cuts" user)
		(27 "Margin" user)
		(31 "F.CrtYd" user "F.Courtyard")
		(29 "B.CrtYd" user "B.Courtyard")
		(35 "F.Fab" user)
		(33 "B.Fab" user)
	)
	(footprint "antmicro-footprints:C_0402_1005Metric"
		(layer "B.Cu")
		(at 219.911 118.704)
		(descr "Capacitor SMD 0402")
		(tags "capacitor SMD 0402")
		(property "Reference" "C214"
			(at 6.539 4.346 0)
			(layer "B.SilkS")
			(effects
				(font
					(size 0.7 0.7)
					(thickness 0.15)
				)
				(justify right bottom mirror)
			)
		)
		(property "Value" "C_100n_0402"
			(at -1.022927 -2.155213 0)
			(layer "B.Fab")
			(hide yes)
			(effects
				(font
					(size 0.7 0.7)
					(thickness 0.15)
				)
				(justify right bottom mirror)
			)
		)
		(property "Datasheet" "https://www.murata.com/products/productdetail?partno=GRM155R61H104KE14%23"
			(at 0 0 0)
			(layer "F.Fab")
			(hide yes)
			(effects
				(font
					(size 1.27 1.27)
					(thickness 0.15)
				)
			)
		)
		(property "Description" "SMD Multilayer Ceramic Capacitor, 0.1 µF, 50 V, 0402 [1005 Metric], ± 10%, X5R, GRM Series"
			(at 0 0 0)
			(layer "F.Fab")
			(hide yes)
			(effects
				(font
					(size 1.27 1.27)
					(thickness 0.15)
				)
			)
		)
		(property "Author" "Antmicro"
			(at 0 0 0)
			(layer "B.Fab")
			(hide yes)
			(effects
				(font
					(size 1 1)
					(thickness 0.15)
				)
				(justify mirror)
			)
		)
		(property "Dielectric" "X5R"
			(at 0 0 0)
			(layer "B.Fab")
			(hide yes)
			(effects
				(font
					(size 1 1)
					(thickness 0.15)
				)
				(justify mirror)
			)
		)
		(property "License" "Apache-2.0"
			(at 0 0 0)
			(layer "B.Fab")
			(hide yes)
			(effects
				(font
					(size 1 1)
					(thickness 0.15)
				)
				(justify mirror)
			)
		)
		(property "MPN" "GRM155R61H104KE14D"
			(at 0 0 0)
			(layer "B.Fab")
			(hide yes)
			(effects
				(font
					(size 1 1)
					(thickness 0.15)
				)
				(justify mirror)
			)
		)
		(property "Manufacturer" "Murata"
			(at 0 0 0)
			(layer "B.Fab")
			(hide yes)
			(effects
				(font
					(size 1 1)
					(thickness 0.15)
				)
				(justify mirror)
			)
		)
		(property "Public" ""
			(at 0 0 0)
			(layer "B.Fab")
			(hide yes)
			(effects
				(font
					(size 1 1)
					(thickness 0.15)
				)
				(justify mirror)
			)
		)
		(property "Val" "100n"
			(at 0 0 0)
			(layer "B.Fab")
			(hide yes)
			(effects
				(font
					(size 1 1)
					(thickness 0.15)
				)
				(justify mirror)
			)
		)
		(property "Voltage" "50V"
			(at 0 0 0)
			(layer "B.Fab")
			(hide yes)
			(effects
				(font
					(size 1 1)
					(thickness 0.15)
				)
				(justify mirror)
			)
		)
		(sheetname "/Ethernet/")
		(sheetfile "ethernet.kicad_sch")
		(attr smd)
		(fp_rect
			(start -0.925 0.47)
			(end 0.925 -0.47)
			(stroke
				(width 0.05)
				(type default)
			)
			(fill no)
			(layer "B.CrtYd")
		)
		(fp_line
			(start -0.494 -0.248)
			(end -0.494 0.25)
			(stroke
				(width 0.15)
				(type solid)
			)
			(layer "B.Fab")
		)
		(fp_line
			(start -0.494 0.25)
			(end 0.504 0.25)
			(stroke
				(width 0.15)
				(type solid)
			)
			(layer "B.Fab")
		)
		(fp_line
			(start 0.504 -0.248)
			(end -0.494 -0.248)
			(stroke
				(width 0.15)
				(type solid)
			)
			(layer "B.Fab")
		)
		(fp_line
			(start 0.504 0.25)
			(end 0.504 -0.248)
			(stroke
				(width 0.15)
				(type solid)
			)
			(layer "B.Fab")
		)
		(fp_text user "Author: Antmicro"
			(at -0.939 -3.399 180)
			(layer "B.Fab")
			(effects
				(font
					(size 0.7 0.7)
					(thickness 0.15)
				)
				(justify left bottom mirror)
			)
		)
		(fp_text user "License: Apache-2.0"
			(at -0.939 -5.799 180)
			(layer "B.Fab")
			(effects
				(font
					(size 0.7 0.7)
					(thickness 0.15)
				)
				(justify left bottom mirror)
			)
		)
		(fp_text user "${REFERENCE}"
			(at -0.939 -4.599 180)
			(layer "B.Fab")
			(effects
				(font
					(size 0.7 0.7)
					(thickness 0.15)
				)
				(justify left bottom mirror)
			)
		)
		(pad "1" smd roundrect
			(at -0.48 0)
			(size 0.59 0.64)
			(layers "B.Cu" "B.Mask" "B.Paste")
			(roundrect_rratio 0.25)
			(net 417 "GND")
			(pintype "passive")
		)
		(pad "2" smd roundrect
			(at 0.48 0)
			(size 0.59 0.64)
			(layers "B.Cu" "B.Mask" "B.Paste")
			(roundrect_rratio 0.25)
			(net 418 "+2V5")
			(pintype "passive")
		)
	)
	(footprint "antmicro-footprints:C_0402_1005Metric"
		(layer "B.Cu")
		(at 213.95 141.3 90)
		(descr "Capacitor SMD 0402")
		(tags "capacitor SMD 0402")
		(property "Reference" "C185"
			(at 0.85 0.11 90)
			(layer "B.SilkS")
			(effects
				(font
					(size 0.7 0.7)
					(thickness 0.15)
				)
				(justify right bottom mirror)
			)
		)
		(property "Value" "C_100n_0402"
			(at -1.022927 -2.155213 90)
			(layer "B.Fab")
			(hide yes)
			(effects
				(font
					(size 0.7 0.7)
					(thickness 0.15)
				)
				(justify right bottom mirror)
			)
		)
		(property "Datasheet" "https://www.murata.com/products/productdetail?partno=GRM155R61H104KE14%23"
			(at 0 0 90)
			(layer "F.Fab")
			(hide yes)
			(effects
				(font
					(size 1.27 1.27)
					(thickness 0.15)
				)
			)
		)
		(property "Description" "SMD Multilayer Ceramic Capacitor, 0.1 µF, 50 V, 0402 [1005 Metric], ± 10%, X5R, GRM Series"
			(at 0 0 90)
			(layer "F.Fab")
			(hide yes)
			(effects
				(font
					(size 1.27 1.27)
					(thickness 0.15)
				)
			)
		)
		(property "Author" "Antmicro"
			(at 355.25 -72.65 0)
			(layer "B.Fab")
			(hide yes)
			(effects
				(font
					(size 1 1)
					(thickness 0.15)
				)
				(justify mirror)
			)
		)
		(property "Dielectric" "X5R"
			(at 355.25 -72.65 0)
			(layer "B.Fab")
			(hide yes)
			(effects
				(font
					(size 1 1)
					(thickness 0.15)
				)
				(justify mirror)
			)
		)
		(property "License" "Apache-2.0"
			(at 355.25 -72.65 0)
			(layer "B.Fab")
			(hide yes)
			(effects
				(font
					(size 1 1)
					(thickness 0.15)
				)
				(justify mirror)
			)
		)
		(property "MPN" "GRM155R61H104KE14D"
			(at 355.25 -72.65 0)
			(layer "B.Fab")
			(hide yes)
			(effects
				(font
					(size 1 1)
					(thickness 0.15)
				)
				(justify mirror)
			)
		)
		(property "Manufacturer" "Murata"
			(at 355.25 -72.65 0)
			(layer "B.Fab")
			(hide yes)
			(effects
				(font
					(size 1 1)
					(thickness 0.15)
				)
				(justify mirror)
			)
		)
		(property "Public" ""
			(at 355.25 -72.65 0)
			(layer "B.Fab")
			(hide yes)
			(effects
				(font
					(size 1 1)
					(thickness 0.15)
				)
				(justify mirror)
			)
		)
		(property "Val" "100n"
			(at 355.25 -72.65 0)
			(layer "B.Fab")
			(hide yes)
			(effects
				(font
					(size 1 1)
					(thickness 0.15)
				)
				(justify mirror)
			)
		)
		(property "Voltage" "50V"
			(at 355.25 -72.65 0)
			(layer "B.Fab")
			(hide yes)
			(effects
				(font
					(size 1 1)
					(thickness 0.15)
				)
				(justify mirror)
			)
		)
		(sheetname "/USB/")
		(sheetfile "usb.kicad_sch")
		(attr smd)
		(fp_rect
			(start -0.925 0.47)
			(end 0.925 -0.47)
			(stroke
				(width 0.05)
				(type default)
			)
			(fill no)
			(layer "B.CrtYd")
		)
		(fp_line
			(start 0.504 -0.248)
			(end -0.494 -0.248)
			(stroke
				(width 0.15)
				(type solid)
			)
			(layer "B.Fab")
		)
		(fp_line
			(start -0.494 -0.248)
			(end -0.494 0.25)
			(stroke
				(width 0.15)
				(type solid)
			)
			(layer "B.Fab")
		)
		(fp_line
			(start 0.504 0.25)
			(end 0.504 -0.248)
			(stroke
				(width 0.15)
				(type solid)
			)
			(layer "B.Fab")
		)
		(fp_line
			(start -0.494 0.25)
			(end 0.504 0.25)
			(stroke
				(width 0.15)
				(type solid)
			)
			(layer "B.Fab")
		)
		(fp_text user "${REFERENCE}"
			(at -0.939 -4.599 270)
			(layer "B.Fab")
			(effects
				(font
					(size 0.7 0.7)
					(thickness 0.15)
				)
				(justify left bottom mirror)
			)
		)
		(fp_text user "Author: Antmicro"
			(at -0.939 -3.399 270)
			(layer "B.Fab")
			(effects
				(font
					(size 0.7 0.7)
					(thickness 0.15)
				)
				(justify left bottom mirror)
			)
		)
		(fp_text user "License: Apache-2.0"
			(at -0.939 -5.799 270)
			(layer "B.Fab")
			(effects
				(font
					(size 0.7 0.7)
					(thickness 0.15)
				)
				(justify left bottom mirror)
			)
		)
		(pad "1" smd roundrect
			(at -0.48 0 90)
			(size 0.59 0.64)
			(layers "B.Cu" "B.Mask" "B.Paste")
			(roundrect_rratio 0.25)
			(net 417 "GND")
			(pintype "passive")
		)
		(pad "2" smd roundrect
			(at 0.48 0 90)
			(size 0.59 0.64)
			(layers "B.Cu" "B.Mask" "B.Paste")
			(roundrect_rratio 0.25)
			(net 152 "/USB/VDDIO")
			(pintype "passive")
		)
	)
	(footprint "antmicro-footprints:C_0402_1005Metric"
		(layer "B.Cu")
		(at 214.361 123.254 -90)
		(descr "Capacitor SMD 0402")
		(tags "capacitor SMD 0402")
		(property "Reference" "C116"
			(at 1.886 -0.589 90)
			(layer "B.SilkS")
			(effects
				(font
					(size 0.7 0.7)
					(thickness 0.15)
				)
				(justify left bottom mirror)
			)
		)
		(property "Value" "C_1u_0402"
			(at -1.022927 -2.155213 90)
			(layer "B.Fab")
			(hide yes)
			(effects
				(font
					(size 0.7 0.7)
					(thickness 0.15)
				)
				(justify left bottom mirror)
			)
		)
		(property "Datasheet" "https://product.tdk.com/en/search/capacitor/ceramic/mlcc/info?part_no=C1005X6S1A105K050BC"
			(at 0 0 270)
			(layer "F.Fab")
			(hide yes)
			(effects
				(font
					(size 1.27 1.27)
					(thickness 0.15)
				)
			)
		)
		(property "Description" "SMD Multilayer Ceramic Capacitor, 1 µF, 10 V, 0402 [1005 Metric], ± 10%, X6S, C"
			(at 0 0 270)
			(layer "F.Fab")
			(hide yes)
			(effects
				(font
					(size 1.27 1.27)
					(thickness 0.15)
				)
			)
		)
		(property "Author" "Antmicro"
			(at 91.107 337.615 0)
			(layer "B.Fab")
			(hide yes)
			(effects
				(font
					(size 1 1)
					(thickness 0.15)
				)
				(justify mirror)
			)
		)
		(property "Dielectric" ""
			(at 91.107 337.615 0)
			(layer "B.Fab")
			(hide yes)
			(effects
				(font
					(size 1 1)
					(thickness 0.15)
				)
				(justify mirror)
			)
		)
		(property "License" "Apache-2.0"
			(at 91.107 337.615 0)
			(layer "B.Fab")
			(hide yes)
			(effects
				(font
					(size 1 1)
					(thickness 0.15)
				)
				(justify mirror)
			)
		)
		(property "MPN" "C1005X6S1A105K050BC"
			(at 91.107 337.615 0)
			(layer "B.Fab")
			(hide yes)
			(effects
				(font
					(size 1 1)
					(thickness 0.15)
				)
				(justify mirror)
			)
		)
		(property "Manufacturer" "TDK"
			(at 91.107 337.615 0)
			(layer "B.Fab")
			(hide yes)
			(effects
				(font
					(size 1 1)
					(thickness 0.15)
				)
				(justify mirror)
			)
		)
		(property "Public" ""
			(at 91.107 337.615 0)
			(layer "B.Fab")
			(hide yes)
			(effects
				(font
					(size 1 1)
					(thickness 0.15)
				)
				(justify mirror)
			)
		)
		(property "Val" "1u"
			(at 91.107 337.615 0)
			(layer "B.Fab")
			(hide yes)
			(effects
				(font
					(size 1 1)
					(thickness 0.15)
				)
				(justify mirror)
			)
		)
		(property "Voltage" ""
			(at 91.107 337.615 0)
			(layer "B.Fab")
			(hide yes)
			(effects
				(font
					(size 1 1)
					(thickness 0.15)
				)
				(justify mirror)
			)
		)
		(sheetname "/Ethernet/")
		(sheetfile "ethernet.kicad_sch")
		(attr smd)
		(fp_rect
			(start -0.925 0.47)
			(end 0.925 -0.47)
			(stroke
				(width 0.05)
				(type default)
			)
			(fill no)
			(layer "B.CrtYd")
		)
		(fp_line
			(start -0.494 0.25)
			(end 0.504 0.25)
			(stroke
				(width 0.15)
				(type solid)
			)
			(layer "B.Fab")
		)
		(fp_line
			(start 0.504 0.25)
			(end 0.504 -0.248)
			(stroke
				(width 0.15)
				(type solid)
			)
			(layer "B.Fab")
		)
		(fp_line
			(start -0.494 -0.248)
			(end -0.494 0.25)
			(stroke
				(width 0.15)
				(type solid)
			)
			(layer "B.Fab")
		)
		(fp_line
			(start 0.504 -0.248)
			(end -0.494 -0.248)
			(stroke
				(width 0.15)
				(type solid)
			)
			(layer "B.Fab")
		)
		(fp_text user "License: Apache-2.0"
			(at -0.939 -5.799 90)
			(layer "B.Fab")
			(effects
				(font
					(size 0.7 0.7)
					(thickness 0.15)
				)
				(justify left bottom mirror)
			)
		)
		(fp_text user "Author: Antmicro"
			(at -0.939 -3.399 90)
			(layer "B.Fab")
			(effects
				(font
					(size 0.7 0.7)
					(thickness 0.15)
				)
				(justify left bottom mirror)
			)
		)
		(fp_text user "${REFERENCE}"
			(at -0.939 -4.599 90)
			(layer "B.Fab")
			(effects
				(font
					(size 0.7 0.7)
					(thickness 0.15)
				)
				(justify left bottom mirror)
			)
		)
		(pad "1" smd roundrect
			(at -0.48 0 270)
			(size 0.59 0.64)
			(layers "B.Cu" "B.Mask" "B.Paste")
			(roundrect_rratio 0.25)
			(net 417 "GND")
			(pintype "passive")
		)
		(pad "2" smd roundrect
			(at 0.48 0 270)
			(size 0.59 0.64)
			(layers "B.Cu" "B.Mask" "B.Paste")
			(roundrect_rratio 0.25)
			(net 50 "+3V3")
			(pintype "passive")
		)
	)
	(footprint "antmicro-footprints:C_0402_1005Metric"
		(layer "B.Cu")
		(at 201.23 148.68)
		(descr "Capacitor SMD 0402")
		(tags "capacitor SMD 0402")
		(property "Reference" "C280"
			(at -1.236 2.275 0)
			(layer "B.SilkS")
			(effects
				(font
					(size 0.7 0.7)
					(thickness 0.15)
				)
				(justify right bottom mirror)
			)
		)
		(property "Value" "C_100n_0402"
			(at -1.022927 -2.155213 0)
			(layer "B.Fab")
			(hide yes)
			(effects
				(font
					(size 0.7 0.7)
					(thickness 0.15)
				)
				(justify right bottom mirror)
			)
		)
		(property "Datasheet" "https://www.murata.com/products/productdetail?partno=GRM155R61H104KE14%23"
			(at 0 0 0)
			(layer "F.Fab")
			(hide yes)
			(effects
				(font
					(size 1.27 1.27)
					(thickness 0.15)
				)
			)
		)
		(property "Description" "SMD Multilayer Ceramic Capacitor, 0.1 µF, 50 V, 0402 [1005 Metric], ± 10%, X5R, GRM Series"
			(at 0 0 0)
			(layer "F.Fab")
			(hide yes)
			(effects
				(font
					(size 1.27 1.27)
					(thickness 0.15)
				)
			)
		)
		(property "Author" "Antmicro"
			(at 0 0 0)
			(layer "B.Fab")
			(hide yes)
			(effects
				(font
					(size 1 1)
					(thickness 0.15)
				)
				(justify mirror)
			)
		)
		(property "Dielectric" "X5R"
			(at 0 0 0)
			(layer "B.Fab")
			(hide yes)
			(effects
				(font
					(size 1 1)
					(thickness 0.15)
				)
				(justify mirror)
			)
		)
		(property "License" "Apache-2.0"
			(at 0 0 0)
			(layer "B.Fab")
			(hide yes)
			(effects
				(font
					(size 1 1)
					(thickness 0.15)
				)
				(justify mirror)
			)
		)
		(property "MPN" "GRM155R61H104KE14D"
			(at 0 0 0)
			(layer "B.Fab")
			(hide yes)
			(effects
				(font
					(size 1 1)
					(thickness 0.15)
				)
				(justify mirror)
			)
		)
		(property "Manufacturer" "Murata"
			(at 0 0 0)
			(layer "B.Fab")
			(hide yes)
			(effects
				(font
					(size 1 1)
					(thickness 0.15)
				)
				(justify mirror)
			)
		)
		(property "Public" ""
			(at 0 0 0)
			(layer "B.Fab")
			(hide yes)
			(effects
				(font
					(size 1 1)
					(thickness 0.15)
				)
				(justify mirror)
			)
		)
		(property "Val" "100n"
			(at 0 0 0)
			(layer "B.Fab")
			(hide yes)
			(effects
				(font
					(size 1 1)
					(thickness 0.15)
				)
				(justify mirror)
			)
		)
		(property "Voltage" "50V"
			(at 0 0 0)
			(layer "B.Fab")
			(hide yes)
			(effects
				(font
					(size 1 1)
					(thickness 0.15)
				)
				(justify mirror)
			)
		)
		(sheetname "/MIPI CrossLink/")
		(sheetfile "crosslink.kicad_sch")
		(attr smd)
		(fp_rect
			(start -0.925 0.47)
			(end 0.925 -0.47)
			(stroke
				(width 0.05)
				(type default)
			)
			(fill no)
			(layer "B.CrtYd")
		)
		(fp_line
			(start -0.494 -0.248)
			(end -0.494 0.25)
			(stroke
				(width 0.15)
				(type solid)
			)
			(layer "B.Fab")
		)
		(fp_line
			(start -0.494 0.25)
			(end 0.504 0.25)
			(stroke
				(width 0.15)
				(type solid)
			)
			(layer "B.Fab")
		)
		(fp_line
			(start 0.504 -0.248)
			(end -0.494 -0.248)
			(stroke
				(width 0.15)
				(type solid)
			)
			(layer "B.Fab")
		)
		(fp_line
			(start 0.504 0.25)
			(end 0.504 -0.248)
			(stroke
				(width 0.15)
				(type solid)
			)
			(layer "B.Fab")
		)
		(fp_text user "Author: Antmicro"
			(at -0.939 -3.399 180)
			(layer "B.Fab")
			(effects
				(font
					(size 0.7 0.7)
					(thickness 0.15)
				)
				(justify left bottom mirror)
			)
		)
		(fp_text user "License: Apache-2.0"
			(at -0.939 -5.799 180)
			(layer "B.Fab")
			(effects
				(font
					(size 0.7 0.7)
					(thickness 0.15)
				)
				(justify left bottom mirror)
			)
		)
		(fp_text user "${REFERENCE}"
			(at -0.939 -4.599 180)
			(layer "B.Fab")
			(effects
				(font
					(size 0.7 0.7)
					(thickness 0.15)
				)
				(justify left bottom mirror)
			)
		)
		(pad "1" smd roundrect
			(at -0.48 0)
			(size 0.59 0.64)
			(layers "B.Cu" "B.Mask" "B.Paste")
			(roundrect_rratio 0.25)
			(net 417 "GND")
			(pintype "passive")
		)
		(pad "2" smd roundrect
			(at 0.48 0)
			(size 0.59 0.64)
			(layers "B.Cu" "B.Mask" "B.Paste")
			(roundrect_rratio 0.25)
			(net 204 "/MIPI CrossLink/CL_VCCPLL_DPHY0")
			(pintype "passive")
		)
	)
)
